(kicad_pcb
	(version 20260206)
	(generator "pcbnew")
	(generator_version "10.0")
	(general
		(thickness 1.6)
		(legacy_teardrops no)
	)
	(paper "A4")
	(title_block
		(title "04192023_DAF0TMB3IC0_F0TG_MB_C_brd_V02_OCP.brd")
		(comment 1 "Grand Teton / footprints 2418-2423 of 8354")
	)
	(layers
		(0 "F.Cu" signal "TOP")
		(4 "In1.Cu" signal "GND")
		(6 "In2.Cu" signal "IN1")
		(8 "In3.Cu" signal "GND1")
		(10 "In4.Cu" signal "IN2")
		(12 "In5.Cu" signal "GND2")
		(14 "In6.Cu" signal "IN3")
		(16 "In7.Cu" signal "GND3")
		(18 "In8.Cu" signal "VCC")
		(20 "In9.Cu" signal "VCC1")
		(22 "In10.Cu" signal "GND4")
		(24 "In11.Cu" signal "IN4")
		(26 "In12.Cu" signal "GND5")
		(28 "In13.Cu" signal "IN5")
		(30 "In14.Cu" signal "GND6")
		(32 "In15.Cu" signal "IN6")
		(34 "In16.Cu" signal "GND7")
		(2 "B.Cu" signal "BOTTOM")
		(9 "F.Adhes" user "F.Adhesive")
		(11 "B.Adhes" user "B.Adhesive")
		(13 "F.Paste" user "Package Geometry/Pastemask Top")
		(15 "B.Paste" user "Package Geometry/Pastemask Bottom")
		(5 "F.SilkS" user "Ref Des/Silkscreen Top")
		(7 "B.SilkS" user "Ref Des/Silkscreen Bottom")
		(1 "F.Mask" user "Board Geometry/Soldermask Top")
		(3 "B.Mask" user "Board Geometry/Soldermask Bottom")
		(17 "Dwgs.User" user "User.Drawings")
		(19 "Cmts.User" user "User.Comments")
		(21 "Eco1.User" user "User.Eco1")
		(23 "Eco2.User" user "User.Eco2")
		(25 "Edge.Cuts" user "Board Geometry/Outline")
		(27 "Margin" user)
		(31 "F.CrtYd" user "Package Geometry/Place Bound Top")
		(29 "B.CrtYd" user "Package Geometry/Place Bound Bottom")
		(35 "F.Fab" user "Ref Des/Assembly Top")
		(33 "B.Fab" user "Ref Des/Assembly Bottom")
	)
	(footprint ""
		(layer "F.Cu")
		(at 178.71694 -404.500842 180)
		(property "Reference" "PR3935"
			(at 0 0 180)
			(layer "F.SilkS")
			(hide yes)
			(effects
				(font
					(size 1.27 1.27)
				)
			)
		)
		(property "Value" ""
			(at 0 0 180)
			(layer "F.Fab")
			(effects
				(font
					(size 1.27 1.27)
				)
			)
		)
		(duplicate_pad_numbers_are_jumpers no)
		(fp_line
			(start 0.7874 0.4064)
			(end -0.7874 0.4064)
			(stroke
				(width 0.1524)
				(type default)
			)
			(layer "F.SilkS")
		)
		(fp_line
			(start 0.7874 -0.4064)
			(end 0.7874 0.4064)
			(stroke
				(width 0.1524)
				(type default)
			)
			(layer "F.SilkS")
		)
		(fp_line
			(start -0.7874 0.4064)
			(end -0.7874 -0.4064)
			(stroke
				(width 0.1524)
				(type default)
			)
			(layer "F.SilkS")
		)
		(fp_line
			(start -0.7874 -0.4064)
			(end 0.7874 -0.4064)
			(stroke
				(width 0.1524)
				(type default)
			)
			(layer "F.SilkS")
		)
		(fp_line
			(start 0.67945 0.3048)
			(end 0.120396 0.3048)
			(stroke
				(width 0.1)
				(type default)
			)
			(layer "F.Fab")
		)
		(fp_line
			(start 0.67945 -0.3048)
			(end 0.67945 0.3048)
			(stroke
				(width 0.1)
				(type default)
			)
			(layer "F.Fab")
		)
		(fp_line
			(start 0.12065 -0.2794)
			(end 0.12065 -0.3048)
			(stroke
				(width 0.1)
				(type default)
			)
			(layer "F.Fab")
		)
		(fp_line
			(start 0.12065 -0.3048)
			(end 0.67945 -0.3048)
			(stroke
				(width 0.1)
				(type default)
			)
			(layer "F.Fab")
		)
		(fp_line
			(start 0.120396 0.3048)
			(end 0.120396 0.2794)
			(stroke
				(width 0.1)
				(type default)
			)
			(layer "F.Fab")
		)
		(fp_line
			(start 0.120396 0.2794)
			(end -0.12065 0.2794)
			(stroke
				(width 0.1)
				(type default)
			)
			(layer "F.Fab")
		)
		(fp_line
			(start -0.12065 0.3048)
			(end -0.67945 0.3048)
			(stroke
				(width 0.1)
				(type default)
			)
			(layer "F.Fab")
		)
		(fp_line
			(start -0.12065 0.2794)
			(end -0.12065 0.3048)
			(stroke
				(width 0.1)
				(type default)
			)
			(layer "F.Fab")
		)
		(fp_line
			(start -0.12065 -0.2794)
			(end 0.12065 -0.2794)
			(stroke
				(width 0.1)
				(type default)
			)
			(layer "F.Fab")
		)
		(fp_line
			(start -0.12065 -0.305054)
			(end -0.12065 -0.2794)
			(stroke
				(width 0.1)
				(type default)
			)
			(layer "F.Fab")
		)
		(fp_line
			(start -0.67945 0.3048)
			(end -0.67945 -0.305054)
			(stroke
				(width 0.1)
				(type default)
			)
			(layer "F.Fab")
		)
		(fp_line
			(start -0.67945 -0.305054)
			(end -0.12065 -0.305054)
			(stroke
				(width 0.1)
				(type default)
			)
			(layer "F.Fab")
		)
		(pad "1" smd circle
			(at -0.40005 0 180)
			(size 0 0)
			(layers "F.Cu" "F.Mask" "F.Paste")
			(net "HSC_VTEMP")
		)
		(pad "2" smd circle
			(at 0.40005 0 180)
			(size 0 0)
			(layers "F.Cu" "F.Mask" "F.Paste")
			(net "AGND_HSC")
		)
	)
	(footprint ""
		(layer "F.Cu")
		(at 167.79621 -394.3604 -90)
		(property "Reference" "R866"
			(at 0 0 270)
			(layer "F.SilkS")
			(hide yes)
			(effects
				(font
					(size 1.27 1.27)
				)
			)
		)
		(property "Value" ""
			(at 0 0 270)
			(layer "F.Fab")
			(effects
				(font
					(size 1.27 1.27)
				)
			)
		)
		(duplicate_pad_numbers_are_jumpers no)
		(fp_line
			(start -0.32512 0.175006)
			(end -0.32512 -0.175006)
			(stroke
				(width 0.1)
				(type default)
			)
			(layer "F.Fab")
		)
		(fp_line
			(start 0.32512 0.175006)
			(end -0.32512 0.175006)
			(stroke
				(width 0.1)
				(type default)
			)
			(layer "F.Fab")
		)
		(fp_line
			(start -0.32512 -0.175006)
			(end 0.32512 -0.175006)
			(stroke
				(width 0.1)
				(type default)
			)
			(layer "F.Fab")
		)
		(fp_line
			(start 0.32512 -0.175006)
			(end 0.32512 0.175006)
			(stroke
				(width 0.1)
				(type default)
			)
			(layer "F.Fab")
		)
		(pad "1" smd rect
			(at -0.2667 0 270)
			(size 0.3048 0.381)
			(layers "F.Cu" "F.Mask" "F.Paste")
			(net "RST_RT_CPU1_P2_PERST_R_N")
		)
		(pad "2" smd rect
			(at 0.2667 0 90)
			(size 0.3048 0.381)
			(layers "F.Cu" "F.Mask" "F.Paste")
			(net "GND")
		)
	)
	(footprint ""
		(layer "F.Cu")
		(at 13.437108 -128.54559 90)
		(property "Reference" "R3341"
			(at 0 0 90)
			(layer "F.SilkS")
			(hide yes)
			(effects
				(font
					(size 1.27 1.27)
				)
			)
		)
		(property "Value" ""
			(at 0 0 90)
			(layer "F.Fab")
			(effects
				(font
					(size 1.27 1.27)
				)
			)
		)
		(duplicate_pad_numbers_are_jumpers no)
		(fp_line
			(start 0.7874 -0.4064)
			(end 0.7874 0.4064)
			(stroke
				(width 0.1524)
				(type default)
			)
			(layer "F.SilkS")
		)
		(fp_line
			(start -0.7874 -0.4064)
			(end 0.7874 -0.4064)
			(stroke
				(width 0.1524)
				(type default)
			)
			(layer "F.SilkS")
		)
		(fp_line
			(start 0.7874 0.4064)
			(end -0.7874 0.4064)
			(stroke
				(width 0.1524)
				(type default)
			)
			(layer "F.SilkS")
		)
		(fp_line
			(start -0.7874 0.4064)
			(end -0.7874 -0.4064)
			(stroke
				(width 0.1524)
				(type default)
			)
			(layer "F.SilkS")
		)
		(fp_line
			(start -0.12065 -0.305054)
			(end -0.12065 -0.2794)
			(stroke
				(width 0.1)
				(type default)
			)
			(layer "F.Fab")
		)
		(fp_line
			(start -0.67945 -0.305054)
			(end -0.12065 -0.305054)
			(stroke
				(width 0.1)
				(type default)
			)
			(layer "F.Fab")
		)
		(fp_line
			(start 0.67945 -0.3048)
			(end 0.67945 0.3048)
			(stroke
				(width 0.1)
				(type default)
			)
			(layer "F.Fab")
		)
		(fp_line
			(start 0.12065 -0.3048)
			(end 0.67945 -0.3048)
			(stroke
				(width 0.1)
				(type default)
			)
			(layer "F.Fab")
		)
		(fp_line
			(start 0.12065 -0.2794)
			(end 0.12065 -0.3048)
			(stroke
				(width 0.1)
				(type default)
			)
			(layer "F.Fab")
		)
		(fp_line
			(start -0.12065 -0.2794)
			(end 0.12065 -0.2794)
			(stroke
				(width 0.1)
				(type default)
			)
			(layer "F.Fab")
		)
		(fp_line
			(start 0.120396 0.2794)
			(end -0.12065 0.2794)
			(stroke
				(width 0.1)
				(type default)
			)
			(layer "F.Fab")
		)
		(fp_line
			(start -0.12065 0.2794)
			(end -0.12065 0.3048)
			(stroke
				(width 0.1)
				(type default)
			)
			(layer "F.Fab")
		)
		(fp_line
			(start 0.67945 0.3048)
			(end 0.120396 0.3048)
			(stroke
				(width 0.1)
				(type default)
			)
			(layer "F.Fab")
		)
		(fp_line
			(start 0.120396 0.3048)
			(end 0.120396 0.2794)
			(stroke
				(width 0.1)
				(type default)
			)
			(layer "F.Fab")
		)
		(fp_line
			(start -0.12065 0.3048)
			(end -0.67945 0.3048)
			(stroke
				(width 0.1)
				(type default)
			)
			(layer "F.Fab")
		)
		(fp_line
			(start -0.67945 0.3048)
			(end -0.67945 -0.305054)
			(stroke
				(width 0.1)
				(type default)
			)
			(layer "F.Fab")
		)
		(pad "1" smd circle
			(at -0.40005 0 90)
			(size 0 0)
			(layers "F.Cu" "F.Mask" "F.Paste")
			(net "SMB_HOST_CLK_3V3AUX_SDA")
		)
		(pad "2" smd circle
			(at 0.40005 0 90)
			(size 0 0)
			(layers "F.Cu" "F.Mask" "F.Paste")
			(net "SMB_HOST_CLK_GEN2_3V3AUX_SDA")
		)
	)
	(footprint ""
		(layer "F.Cu")
		(at 228.827076 -294.597074 180)
		(property "Reference" "PR6801"
			(at 0 0 180)
			(layer "F.SilkS")
			(hide yes)
			(effects
				(font
					(size 1.27 1.27)
				)
			)
		)
		(property "Value" ""
			(at 0 0 180)
			(layer "F.Fab")
			(effects
				(font
					(size 1.27 1.27)
				)
			)
		)
		(duplicate_pad_numbers_are_jumpers no)
		(fp_line
			(start 0.7874 0.4064)
			(end -0.7874 0.4064)
			(stroke
				(width 0.1524)
				(type default)
			)
			(layer "F.SilkS")
		)
		(fp_line
			(start 0.7874 -0.4064)
			(end 0.7874 0.4064)
			(stroke
				(width 0.1524)
				(type default)
			)
			(layer "F.SilkS")
		)
		(fp_line
			(start -0.7874 0.4064)
			(end -0.7874 -0.4064)
			(stroke
				(width 0.1524)
				(type default)
			)
			(layer "F.SilkS")
		)
		(fp_line
			(start -0.7874 -0.4064)
			(end 0.7874 -0.4064)
			(stroke
				(width 0.1524)
				(type default)
			)
			(layer "F.SilkS")
		)
		(fp_line
			(start 0.67945 0.3048)
			(end 0.120396 0.3048)
			(stroke
				(width 0.1)
				(type default)
			)
			(layer "F.Fab")
		)
		(fp_line
			(start 0.67945 -0.3048)
			(end 0.67945 0.3048)
			(stroke
				(width 0.1)
				(type default)
			)
			(layer "F.Fab")
		)
		(fp_line
			(start 0.12065 -0.2794)
			(end 0.12065 -0.3048)
			(stroke
				(width 0.1)
				(type default)
			)
			(layer "F.Fab")
		)
		(fp_line
			(start 0.12065 -0.3048)
			(end 0.67945 -0.3048)
			(stroke
				(width 0.1)
				(type default)
			)
			(layer "F.Fab")
		)
		(fp_line
			(start 0.120396 0.3048)
			(end 0.120396 0.2794)
			(stroke
				(width 0.1)
				(type default)
			)
			(layer "F.Fab")
		)
		(fp_line
			(start 0.120396 0.2794)
			(end -0.12065 0.2794)
			(stroke
				(width 0.1)
				(type default)
			)
			(layer "F.Fab")
		)
		(fp_line
			(start -0.12065 0.3048)
			(end -0.67945 0.3048)
			(stroke
				(width 0.1)
				(type default)
			)
			(layer "F.Fab")
		)
		(fp_line
			(start -0.12065 0.2794)
			(end -0.12065 0.3048)
			(stroke
				(width 0.1)
				(type default)
			)
			(layer "F.Fab")
		)
		(fp_line
			(start -0.12065 -0.2794)
			(end 0.12065 -0.2794)
			(stroke
				(width 0.1)
				(type default)
			)
			(layer "F.Fab")
		)
		(fp_line
			(start -0.12065 -0.305054)
			(end -0.12065 -0.2794)
			(stroke
				(width 0.1)
				(type default)
			)
			(layer "F.Fab")
		)
		(fp_line
			(start -0.67945 0.3048)
			(end -0.67945 -0.305054)
			(stroke
				(width 0.1)
				(type default)
			)
			(layer "F.Fab")
		)
		(fp_line
			(start -0.67945 -0.305054)
			(end -0.12065 -0.305054)
			(stroke
				(width 0.1)
				(type default)
			)
			(layer "F.Fab")
		)
		(pad "1" smd circle
			(at -0.40005 0 180)
			(size 0 0)
			(layers "F.Cu" "F.Mask" "F.Paste")
			(net "SW_P1V8_RETIMER_CPU1_BST")
		)
		(pad "2" smd circle
			(at 0.40005 0 180)
			(size 0 0)
			(layers "F.Cu" "F.Mask" "F.Paste")
			(net "SW_P1V8_RETIMER_CPU1_BST_R")
		)
	)
	(footprint ""
		(layer "F.Cu")
		(at 397.824198 -177.171096 180)
		(property "Reference" "PU49"
			(at 4.331716 -6.338062 0)
			(unlocked yes)
			(layer "F.SilkS")
			(effects
				(font
					(size 0.7874 0.5842)
					(thickness 0.1524)
				)
				(justify left)
			)
		)
		(property "Value" ""
			(at 0 0 180)
			(layer "F.Fab")
			(effects
				(font
					(size 1.27 1.27)
				)
			)
		)
		(duplicate_pad_numbers_are_jumpers no)
		(fp_line
			(start 2.500122 2.999994)
			(end 2.2987 2.999994)
			(stroke
				(width 0.1524)
				(type default)
			)
			(layer "F.SilkS")
		)
		(fp_line
			(start 2.500122 2.339594)
			(end 2.500122 2.999994)
			(stroke
				(width 0.1524)
				(type default)
			)
			(layer "F.SilkS")
		)
		(fp_line
			(start 2.500122 -2.999994)
			(end 2.500122 -2.44348)
			(stroke
				(width 0.1524)
				(type default)
			)
			(layer "F.SilkS")
		)
		(fp_line
			(start 2.31394 -2.999994)
			(end 2.500122 -2.999994)
			(stroke
				(width 0.1524)
				(type default)
			)
			(layer "F.SilkS")
		)
		(fp_line
			(start -2.2987 2.999994)
			(end -2.500122 2.999994)
			(stroke
				(width 0.1524)
				(type default)
			)
			(layer "F.SilkS")
		)
		(fp_line
			(start -2.500122 2.999994)
			(end -2.500122 2.339594)
			(stroke
				(width 0.1524)
				(type default)
			)
			(layer "F.SilkS")
		)
		(fp_line
			(start -2.500122 0.6604)
			(end -2.500122 0.229108)
			(stroke
				(width 0.1524)
				(type default)
			)
			(layer "F.SilkS")
		)
		(fp_line
			(start -2.500122 -2.529078)
			(end -2.500122 -2.999994)
			(stroke
				(width 0.1524)
				(type default)
			)
			(layer "F.SilkS")
		)
		(fp_line
			(start -2.500122 -2.999994)
			(end -2.24409 -2.999994)
			(stroke
				(width 0.1524)
				(type default)
			)
			(layer "F.SilkS")
		)
		(fp_poly
			(pts
				(xy -2.695448 -2.471928) (xy -3.476244 -2.732278) (xy -2.955798 -3.252978)
			)
			(stroke
				(width 0)
				(type default)
			)
			(fill yes)
			(layer "F.SilkS")
		)
		(fp_line
			(start 2.500122 2.999994)
			(end -2.500122 2.999994)
			(stroke
				(width 0.1)
				(type default)
			)
			(layer "F.Fab")
		)
		(fp_line
			(start 2.500122 -2.999994)
			(end 2.500122 2.999994)
			(stroke
				(width 0.1)
				(type default)
			)
			(layer "F.Fab")
		)
		(fp_line
			(start -2.500122 2.999994)
			(end -2.500122 -2.999994)
			(stroke
				(width 0.1)
				(type default)
			)
			(layer "F.Fab")
		)
		(fp_line
			(start -2.500122 -2.999994)
			(end 2.500122 -2.999994)
			(stroke
				(width 0.1)
				(type default)
			)
			(layer "F.Fab")
		)
		(fp_poly
			(pts
				(xy -4.218432 -2.783078) (xy -4.218432 -1.767078) (xy -3.202432 -2.275078)
			)
			(stroke
				(width 0)
				(type default)
			)
			(fill yes)
			(layer "F.Fab")
		)
		(pad "1" smd rect
			(at -2.400046 -2.275078 270)
			(size 0.2286 0.6096)
			(layers "F.Cu" "F.Mask" "F.Paste")
			(net "PVDDCR_SOC_P0_VOS1")
		)
		(pad "2" smd rect
			(at -2.400046 -1.82499 270)
			(size 0.2286 0.6096)
			(layers "F.Cu" "F.Mask" "F.Paste")
			(net "GND")
		)
		(pad "3" smd rect
			(at -2.400046 -1.374902 270)
			(size 0.2286 0.6096)
			(layers "F.Cu" "F.Mask" "F.Paste")
			(net "PVDDCR_SOC_P0_VCC1")
		)
		(pad "4" smd rect
			(at -2.400046 -0.925068 270)
			(size 0.2286 0.6096)
			(layers "F.Cu" "F.Mask" "F.Paste")
			(net "PVDDCR_CPU0_P0_PVCC")
		)
		(pad "5" smd rect
			(at -2.400046 -0.47498 270)
			(size 0.2286 0.6096)
			(layers "F.Cu" "F.Mask" "F.Paste")
			(net "GND")
		)
		(pad "6" smd rect
			(at -2.400046 -0.024892 270)
			(size 0.2286 0.6096)
			(layers "F.Cu" "F.Mask" "F.Paste")
			(net "NC_PVDDCR_SOC_P0_GL1_1")
		)
		(pad "7_9-20_24" smd circle
			(at 0 1.150112 270)
			(size 0 0)
			(layers "F.Cu" "F.Mask" "F.Paste")
			(net "GND")
		)
		(pad "10_19" smd rect
			(at 0 2.899918 270)
			(size 0.6096 4.318)
			(layers "F.Cu" "F.Mask" "F.Paste")
			(net "SW_PVDDCR_SOC_P0_SW1")
		)
		(pad "25_29" smd rect
			(at 1.549908 -1.279906 90)
			(size 2.0574 2.3114)
			(layers "F.Cu" "F.Mask" "F.Paste")
			(net "SW_P12V_AUX_PVDDCR_SOC_P0_FLT")
		)
		(pad "30" smd rect
			(at 2.05994 -2.899918 180)
			(size 0.2286 0.6096)
			(layers "F.Cu" "F.Mask" "F.Paste")
			(net "SW_P12V_AUX_PVDDCR_SOC_P0_FLT")
		)
		(pad "31" smd rect
			(at 1.610106 -2.899918 180)
			(size 0.2286 0.6096)
			(layers "F.Cu" "F.Mask" "F.Paste")
			(net "NC_PVDDCR_SOC_P0_DNC1")
		)
		(pad "32" smd rect
			(at 1.160018 -2.899918 180)
			(size 0.2286 0.6096)
			(layers "F.Cu" "F.Mask" "F.Paste")
			(net "SW_PVDDCR_SOC_P0_PH1")
		)
		(pad "33" smd rect
			(at 0.70993 -2.899918 180)
			(size 0.2286 0.6096)
			(layers "F.Cu" "F.Mask" "F.Paste")
			(net "SW_PVDDCR_SOC_P0_BOOT1")
		)
		(pad "34" smd rect
			(at 0.260096 -2.899918 180)
			(size 0.2286 0.6096)
			(layers "F.Cu" "F.Mask" "F.Paste")
			(net "PVDDCR_SOC_P0_PWM1")
		)
		(pad "35" smd rect
			(at -0.189992 -2.899918 180)
			(size 0.2286 0.6096)
			(layers "F.Cu" "F.Mask" "F.Paste")
			(net "PVDDCR_SOC_P0_VCC1")
		)
		(pad "36" smd rect
			(at -0.64008 -2.899918 180)
			(size 0.2286 0.6096)
			(layers "F.Cu" "F.Mask" "F.Paste")
			(net "PVDDCR_SOC_P0_TEMP1")
		)
		(pad "37" smd rect
			(at -1.089914 -2.899918 180)
			(size 0.2286 0.6096)
			(layers "F.Cu" "F.Mask" "F.Paste")
			(net "PVDDCR_SOC_P0_LSET1")
		)
		(pad "38" smd rect
			(at -1.540002 -2.899918 180)
			(size 0.2286 0.6096)
			(layers "F.Cu" "F.Mask" "F.Paste")
			(net "PVDDCR_SOC_P0_IMON1")
		)
		(pad "39" smd rect
			(at -1.99009 -2.899918 180)
			(size 0.2286 0.6096)
			(layers "F.Cu" "F.Mask" "F.Paste")
			(net "PVDDCR_CPU0_P0_VCCS")
		)
		(pad "40" smd rect
			(at -0.87503 -1.27508 180)
			(size 1.7526 1.9558)
			(layers "F.Cu" "F.Mask" "F.Paste")
			(net "GND")
		)
		(pad "41" smd rect
			(at -1.525016 0.249936 90)
			(size 0.3048 0.4572)
			(layers "F.Cu" "F.Mask" "F.Paste")
			(net "NC_PVDDCR_SOC_P0_GL2_1")
		)
		(zone
			(layer "F.Cu")
			(hatch none 0.5)
			(connect_pads
				(clearance 0)
			)
			(min_thickness 0.25)
			(keepout
				(tracks not_allowed)
				(vias allowed)
				(pads allowed)
				(copperpour not_allowed)
				(footprints allowed)
			)
			(placement
				(enabled no)
				(sheetname "")
			)
			(fill
				(thermal_gap 0.5)
				(thermal_bridge_width 0.5)
				(island_removal_mode 0)
			)
			(polygon
				(pts
					(xy 400.32432 -179.75453) (xy 400.32432 -179.42179) (xy 395.324076 -179.42179) (xy 395.324076 -179.747418)
					(xy 395.614398 -179.747418) (xy 395.614398 -179.715414) (xy 400.033998 -179.715414) (xy 400.033998 -179.75453)
				)
			)
		)
		(zone
			(layer "F.Cu")
			(hatch none 0.5)
			(connect_pads
				(clearance 0)
			)
			(min_thickness 0.25)
			(keepout
				(tracks not_allowed)
				(vias allowed)
				(pads allowed)
				(copperpour not_allowed)
				(footprints allowed)
			)
			(placement
				(enabled no)
				(sheetname "")
			)
			(fill
				(thermal_gap 0.5)
				(thermal_bridge_width 0.5)
				(island_removal_mode 0)
			)
			(polygon
				(pts
					(xy 397.772128 -176.924716) (xy 397.772128 -174.867316) (xy 399.626328 -174.867316) (xy 399.626328 -175.108362)
					(xy 399.868644 -175.108362) (xy 399.868644 -174.626778) (xy 395.960346 -174.626778) (xy 395.960346 -174.81169)
					(xy 397.48079 -174.81169) (xy 397.48079 -176.97069) (xy 395.324076 -176.97069) (xy 395.324076 -177.220372)
					(xy 397.472408 -177.220372) (xy 397.74876 -176.94402) (xy 397.752824 -176.94402)
				)
			)
		)
	)
	(footprint ""
		(layer "F.Cu")
		(at 54.594506 19.444716 -90)
		(property "Reference" "J90_CON"
			(at 0 0 270)
			(layer "F.SilkS")
			(hide yes)
			(effects
				(font
					(size 1.27 1.27)
				)
			)
		)
		(property "Value" ""
			(at 0 0 270)
			(layer "F.Fab")
			(effects
				(font
					(size 1.27 1.27)
				)
			)
		)
		(duplicate_pad_numbers_are_jumpers no)
		(pad "1" smd circle
			(at 0 0 270)
			(size 0.762 0.762)
			(layers "F.Cu" "F.Mask" "F.Paste")
			(net "Net_2617")
		)
	)
)
